(kicad_pcb
	(version 20260206)
	(generator "pcbnew")
	(generator_version "10.0")
	(general
		(thickness 1.6)
		(legacy_teardrops no)
	)
	(paper "A4")
	(title_block
		(title "Wiwynn_Tioga_Pass_MB.brd")
		(comment 1 "Tioga Pass / footprints 695-702 of 4770")
	)
	(layers
		(0 "F.Cu" signal "TOP")
		(4 "In1.Cu" signal "L2GND")
		(6 "In2.Cu" signal "L3")
		(8 "In3.Cu" signal "L4GND")
		(10 "In4.Cu" signal "L5")
		(12 "In5.Cu" signal "L6GND")
		(14 "In6.Cu" signal "L7VCC")
		(16 "In7.Cu" signal "L8VCC")
		(18 "In8.Cu" signal "L9GND")
		(20 "In9.Cu" signal "L10")
		(22 "In10.Cu" signal "L11GND")
		(24 "In11.Cu" signal "L12")
		(26 "In12.Cu" signal "L13GND")
		(2 "B.Cu" signal "BOTTOM")
		(9 "F.Adhes" user "F.Adhesive")
		(11 "B.Adhes" user "B.Adhesive")
		(13 "F.Paste" user "Package Geometry/Pastemask Top")
		(15 "B.Paste" user "Package Geometry/Pastemask Bottom")
		(5 "F.SilkS" user "Ref Des/Silkscreen Top")
		(7 "B.SilkS" user "Ref Des/Silkscreen Bottom")
		(1 "F.Mask" user "Board Geometry/Soldermask Top")
		(3 "B.Mask" user "Board Geometry/Soldermask Bottom")
		(17 "Dwgs.User" user "User.Drawings")
		(19 "Cmts.User" user "User.Comments")
		(21 "Eco1.User" user "User.Eco1")
		(23 "Eco2.User" user "User.Eco2")
		(25 "Edge.Cuts" user "Board Geometry/Outline")
		(27 "Margin" user)
		(31 "F.CrtYd" user "Package Geometry/Place Bound Top")
		(29 "B.CrtYd" user "Package Geometry/Place Bound Bottom")
		(35 "F.Fab" user "Ref Des/Assembly Top")
		(33 "B.Fab" user "Ref Des/Assembly Bottom")
	)
	(footprint ""
		(layer "F.Cu")
		(at 399.542 -146.5326)
		(property "Reference" ""
			(at 0 0 0)
			(layer "F.SilkS")
			(hide yes)
			(effects
				(font
					(size 1.27 1.27)
				)
			)
		)
		(property "Value" ""
			(at 0 0 0)
			(layer "F.Fab")
			(effects
				(font
					(size 1.27 1.27)
				)
			)
		)
		(duplicate_pad_numbers_are_jumpers no)
		(fp_poly
			(pts
				(arc
					(start 2.032 0)
					(mid -2.032 0)
					(end 2.032 0)
				)
			)
			(stroke
				(width 0)
				(type default)
			)
			(fill no)
			(layer "F.CrtYd")
		)
		(pad "1" smd circle
			(at 0 0)
			(size 1.016 1.016)
			(layers "F.Cu" "F.Mask" "F.Paste")
			(net "Net_133")
		)
		(zone
			(layer "F.Cu")
			(hatch none 0.5)
			(connect_pads
				(clearance 0)
			)
			(min_thickness 0.25)
			(keepout
				(tracks not_allowed)
				(vias allowed)
				(pads allowed)
				(copperpour not_allowed)
				(footprints allowed)
			)
			(placement
				(enabled no)
				(sheetname "")
			)
			(fill
				(thermal_gap 0.5)
				(thermal_bridge_width 0.5)
				(island_removal_mode 0)
			)
			(polygon
				(pts
					(arc
						(start 401.066 -146.5326)
						(mid 398.018 -146.5326)
						(end 401.066 -146.5326)
					)
				)
			)
		)
		(zone
			(layers "F.Cu" "B.Cu" "In1.Cu" "In2.Cu" "In3.Cu" "In4.Cu" "In5.Cu" "In6.Cu"
				"In7.Cu" "In8.Cu" "In9.Cu" "In10.Cu" "In11.Cu" "In12.Cu"
			)
			(hatch none 0.5)
			(connect_pads
				(clearance 0)
			)
			(min_thickness 0.25)
			(keepout
				(tracks allowed)
				(vias not_allowed)
				(pads allowed)
				(copperpour not_allowed)
				(footprints allowed)
			)
			(placement
				(enabled no)
				(sheetname "")
			)
			(fill
				(thermal_gap 0.5)
				(thermal_bridge_width 0.5)
				(island_removal_mode 0)
			)
			(polygon
				(pts
					(arc
						(start 401.066 -146.5326)
						(mid 398.018 -146.5326)
						(end 401.066 -146.5326)
					)
				)
			)
		)
	)
	(footprint ""
		(layer "F.Cu")
		(at 165.9763 -133.1976)
		(property "Reference" "C4B2"
			(at 0 0 0)
			(layer "F.SilkS")
			(hide yes)
			(effects
				(font
					(size 1.27 1.27)
				)
			)
		)
		(property "Value" ""
			(at 0 0 0)
			(layer "F.Fab")
			(effects
				(font
					(size 1.27 1.27)
				)
			)
		)
		(duplicate_pad_numbers_are_jumpers no)
		(fp_poly
			(pts
				(xy -0.7239 -0.2159) (xy 0.7239 -0.2159) (xy 0.7239 1.9939) (xy -0.7239 1.9939)
			)
			(stroke
				(width 0)
				(type default)
			)
			(fill no)
			(layer "F.CrtYd")
		)
		(fp_line
			(start -0.7239 -0.2159)
			(end -0.7239 1.9939)
			(stroke
				(width 0.1)
				(type default)
			)
			(layer "F.Fab")
		)
		(fp_line
			(start -0.7239 1.9939)
			(end 0.7239 1.9939)
			(stroke
				(width 0.1)
				(type default)
			)
			(layer "F.Fab")
		)
		(fp_line
			(start 0.7239 -0.2159)
			(end -0.7239 -0.2159)
			(stroke
				(width 0.1)
				(type default)
			)
			(layer "F.Fab")
		)
		(fp_line
			(start 0.7239 1.9939)
			(end 0.7239 -0.2159)
			(stroke
				(width 0.1)
				(type default)
			)
			(layer "F.Fab")
		)
		(pad "1" smd rect
			(at 0 0)
			(size 1.27 1.016)
			(layers "F.Cu" "F.Mask" "F.Paste")
			(net "PVPP_KLM")
		)
		(pad "2" smd rect
			(at 0 1.778)
			(size 1.27 1.016)
			(layers "F.Cu" "F.Mask" "F.Paste")
			(net "GND")
		)
		(zone
			(layer "F.Cu")
			(hatch none 0.5)
			(connect_pads
				(clearance 0)
			)
			(min_thickness 0.25)
			(keepout
				(tracks not_allowed)
				(vias allowed)
				(pads allowed)
				(copperpour not_allowed)
				(footprints allowed)
			)
			(placement
				(enabled no)
				(sheetname "")
			)
			(fill
				(thermal_gap 0.5)
				(thermal_bridge_width 0.5)
				(island_removal_mode 0)
			)
			(polygon
				(pts
					(xy 165.3413 -132.6896) (xy 166.6113 -132.6896) (xy 166.6113 -131.9276) (xy 165.3413 -131.9276)
				)
			)
		)
	)
	(footprint ""
		(layer "F.Cu")
		(at 471.5891 -43.0784 -90)
		(property "Reference" "C9F6"
			(at 0 0 270)
			(layer "F.SilkS")
			(hide yes)
			(effects
				(font
					(size 1.27 1.27)
				)
			)
		)
		(property "Value" ""
			(at 0 0 270)
			(layer "F.Fab")
			(effects
				(font
					(size 1.27 1.27)
				)
			)
		)
		(duplicate_pad_numbers_are_jumpers no)
		(fp_poly
			(pts
				(xy 0.3048 -0.1016) (xy 0.3048 0.9906) (xy -0.3048 0.9906) (xy -0.3048 -0.1016)
			)
			(stroke
				(width 0)
				(type default)
			)
			(fill no)
			(layer "F.CrtYd")
		)
		(fp_line
			(start -0.3048 0.9906)
			(end 0.3048 0.9906)
			(stroke
				(width 0.1)
				(type default)
			)
			(layer "F.Fab")
		)
		(fp_line
			(start 0.3048 0.9906)
			(end 0.3048 -0.1016)
			(stroke
				(width 0.1)
				(type default)
			)
			(layer "F.Fab")
		)
		(fp_line
			(start -0.3048 -0.1016)
			(end -0.3048 0.9906)
			(stroke
				(width 0.1)
				(type default)
			)
			(layer "F.Fab")
		)
		(fp_line
			(start 0.3048 -0.1016)
			(end -0.3048 -0.1016)
			(stroke
				(width 0.1)
				(type default)
			)
			(layer "F.Fab")
		)
		(pad "1" smd rect
			(at 0 0 270)
			(size 0.508 0.508)
			(layers "F.Cu" "F.Mask" "F.Paste")
			(net "PWRGD_P2V5_BMC_STBY")
		)
		(pad "2" smd rect
			(at 0 0.889 270)
			(size 0.508 0.508)
			(layers "F.Cu" "F.Mask" "F.Paste")
			(net "GND")
		)
		(zone
			(layer "F.Cu")
			(hatch none 0.5)
			(connect_pads
				(clearance 0)
			)
			(min_thickness 0.25)
			(keepout
				(tracks not_allowed)
				(vias allowed)
				(pads allowed)
				(copperpour not_allowed)
				(footprints allowed)
			)
			(placement
				(enabled no)
				(sheetname "")
			)
			(fill
				(thermal_gap 0.5)
				(thermal_bridge_width 0.5)
				(island_removal_mode 0)
			)
			(polygon
				(pts
					(xy 470.9541 -43.3324) (xy 470.9541 -42.8244) (xy 471.3351 -42.8244) (xy 471.3351 -43.3324)
				)
			)
		)
		(zone
			(layer "F.Cu")
			(hatch none 0.5)
			(connect_pads
				(clearance 0)
			)
			(min_thickness 0.25)
			(keepout
				(tracks allowed)
				(vias not_allowed)
				(pads allowed)
				(copperpour not_allowed)
				(footprints allowed)
			)
			(placement
				(enabled no)
				(sheetname "")
			)
			(fill
				(thermal_gap 0.5)
				(thermal_bridge_width 0.5)
				(island_removal_mode 0)
			)
			(polygon
				(pts
					(xy 471.3351 -43.3324) (xy 471.3351 -42.8244) (xy 470.9541 -42.8244) (xy 470.9541 -43.3324)
				)
			)
		)
	)
	(footprint ""
		(layer "F.Cu")
		(at 26.898092 -13.3985)
		(property "Reference" "C1G8"
			(at 0 0 0)
			(layer "F.SilkS")
			(hide yes)
			(effects
				(font
					(size 1.27 1.27)
				)
			)
		)
		(property "Value" ""
			(at 0 0 0)
			(layer "F.Fab")
			(effects
				(font
					(size 1.27 1.27)
				)
			)
		)
		(duplicate_pad_numbers_are_jumpers no)
		(fp_poly
			(pts
				(xy 0.3048 -0.1016) (xy 0.3048 0.9906) (xy -0.3048 0.9906) (xy -0.3048 -0.1016)
			)
			(stroke
				(width 0)
				(type default)
			)
			(fill no)
			(layer "F.CrtYd")
		)
		(fp_line
			(start -0.3048 -0.1016)
			(end -0.3048 0.9906)
			(stroke
				(width 0.1)
				(type default)
			)
			(layer "F.Fab")
		)
		(fp_line
			(start -0.3048 0.9906)
			(end 0.3048 0.9906)
			(stroke
				(width 0.1)
				(type default)
			)
			(layer "F.Fab")
		)
		(fp_line
			(start 0.3048 -0.1016)
			(end -0.3048 -0.1016)
			(stroke
				(width 0.1)
				(type default)
			)
			(layer "F.Fab")
		)
		(fp_line
			(start 0.3048 0.9906)
			(end 0.3048 -0.1016)
			(stroke
				(width 0.1)
				(type default)
			)
			(layer "F.Fab")
		)
		(pad "1" smd rect
			(at 0 0)
			(size 0.508 0.508)
			(layers "F.Cu" "F.Mask" "F.Paste")
			(net "M_H_CPU_VREF")
		)
		(pad "2" smd rect
			(at 0 0.889)
			(size 0.508 0.508)
			(layers "F.Cu" "F.Mask" "F.Paste")
			(net "GND")
		)
		(zone
			(layer "F.Cu")
			(hatch none 0.5)
			(connect_pads
				(clearance 0)
			)
			(min_thickness 0.25)
			(keepout
				(tracks allowed)
				(vias not_allowed)
				(pads allowed)
				(copperpour not_allowed)
				(footprints allowed)
			)
			(placement
				(enabled no)
				(sheetname "")
			)
			(fill
				(thermal_gap 0.5)
				(thermal_bridge_width 0.5)
				(island_removal_mode 0)
			)
			(polygon
				(pts
					(xy 26.644092 -13.1445) (xy 27.152092 -13.1445) (xy 27.152092 -12.7635) (xy 26.644092 -12.7635)
				)
			)
		)
		(zone
			(layer "F.Cu")
			(hatch none 0.5)
			(connect_pads
				(clearance 0)
			)
			(min_thickness 0.25)
			(keepout
				(tracks not_allowed)
				(vias allowed)
				(pads allowed)
				(copperpour not_allowed)
				(footprints allowed)
			)
			(placement
				(enabled no)
				(sheetname "")
			)
			(fill
				(thermal_gap 0.5)
				(thermal_bridge_width 0.5)
				(island_removal_mode 0)
			)
			(polygon
				(pts
					(xy 26.644092 -12.7635) (xy 27.152092 -12.7635) (xy 27.152092 -13.1445) (xy 26.644092 -13.1445)
				)
			)
		)
	)
	(footprint ""
		(layer "F.Cu")
		(at 176.0855 -131.318 90)
		(property "Reference" "C4B9"
			(at 0 0 90)
			(layer "F.SilkS")
			(hide yes)
			(effects
				(font
					(size 1.27 1.27)
				)
			)
		)
		(property "Value" ""
			(at 0 0 90)
			(layer "F.Fab")
			(effects
				(font
					(size 1.27 1.27)
				)
			)
		)
		(duplicate_pad_numbers_are_jumpers no)
		(fp_poly
			(pts
				(xy 0.3048 -0.1016) (xy 0.3048 0.9906) (xy -0.3048 0.9906) (xy -0.3048 -0.1016)
			)
			(stroke
				(width 0)
				(type default)
			)
			(fill no)
			(layer "F.CrtYd")
		)
		(fp_line
			(start 0.3048 -0.1016)
			(end -0.3048 -0.1016)
			(stroke
				(width 0.1)
				(type default)
			)
			(layer "F.Fab")
		)
		(fp_line
			(start -0.3048 -0.1016)
			(end -0.3048 0.9906)
			(stroke
				(width 0.1)
				(type default)
			)
			(layer "F.Fab")
		)
		(fp_line
			(start 0.3048 0.9906)
			(end 0.3048 -0.1016)
			(stroke
				(width 0.1)
				(type default)
			)
			(layer "F.Fab")
		)
		(fp_line
			(start -0.3048 0.9906)
			(end 0.3048 0.9906)
			(stroke
				(width 0.1)
				(type default)
			)
			(layer "F.Fab")
		)
		(pad "1" smd rect
			(at 0 0 90)
			(size 0.508 0.508)
			(layers "F.Cu" "F.Mask" "F.Paste")
			(net "VR_COMP_RC_PVPP_KLM")
		)
		(pad "2" smd rect
			(at 0 0.889 90)
			(size 0.508 0.508)
			(layers "F.Cu" "F.Mask" "F.Paste")
			(net "VR_COMP_PVPP_KLM_3")
		)
		(zone
			(layer "F.Cu")
			(hatch none 0.5)
			(connect_pads
				(clearance 0)
			)
			(min_thickness 0.25)
			(keepout
				(tracks allowed)
				(vias not_allowed)
				(pads allowed)
				(copperpour not_allowed)
				(footprints allowed)
			)
			(placement
				(enabled no)
				(sheetname "")
			)
			(fill
				(thermal_gap 0.5)
				(thermal_bridge_width 0.5)
				(island_removal_mode 0)
			)
			(polygon
				(pts
					(xy 176.3395 -131.064) (xy 176.3395 -131.572) (xy 176.7205 -131.572) (xy 176.7205 -131.064)
				)
			)
		)
		(zone
			(layer "F.Cu")
			(hatch none 0.5)
			(connect_pads
				(clearance 0)
			)
			(min_thickness 0.25)
			(keepout
				(tracks not_allowed)
				(vias allowed)
				(pads allowed)
				(copperpour not_allowed)
				(footprints allowed)
			)
			(placement
				(enabled no)
				(sheetname "")
			)
			(fill
				(thermal_gap 0.5)
				(thermal_bridge_width 0.5)
				(island_removal_mode 0)
			)
			(polygon
				(pts
					(xy 176.7205 -131.064) (xy 176.7205 -131.572) (xy 176.3395 -131.572) (xy 176.3395 -131.064)
				)
			)
		)
	)
	(footprint ""
		(layer "F.Cu")
		(at 488.974638 -28.42768 180)
		(property "Reference" "R9F25"
			(at 0 0 180)
			(layer "F.SilkS")
			(hide yes)
			(effects
				(font
					(size 1.27 1.27)
				)
			)
		)
		(property "Value" ""
			(at 0 0 180)
			(layer "F.Fab")
			(effects
				(font
					(size 1.27 1.27)
				)
			)
		)
		(duplicate_pad_numbers_are_jumpers no)
		(fp_poly
			(pts
				(xy -0.2794 -0.1016) (xy 0.2794 -0.1016) (xy 0.2794 0.9906) (xy -0.2794 0.9906)
			)
			(stroke
				(width 0)
				(type default)
			)
			(fill no)
			(layer "F.CrtYd")
		)
		(fp_line
			(start 0.2794 0.9906)
			(end 0.2794 -0.1016)
			(stroke
				(width 0.1)
				(type default)
			)
			(layer "F.Fab")
		)
		(fp_line
			(start 0.2794 -0.1016)
			(end -0.2794 -0.1016)
			(stroke
				(width 0.1)
				(type default)
			)
			(layer "F.Fab")
		)
		(fp_line
			(start -0.2794 0.9906)
			(end 0.2794 0.9906)
			(stroke
				(width 0.1)
				(type default)
			)
			(layer "F.Fab")
		)
		(fp_line
			(start -0.2794 -0.1016)
			(end -0.2794 0.9906)
			(stroke
				(width 0.1)
				(type default)
			)
			(layer "F.Fab")
		)
		(pad "1" smd rect
			(at 0 0 180)
			(size 0.508 0.508)
			(layers "F.Cu" "F.Mask" "F.Paste")
			(net "SPA_MID_DBG_RX")
		)
		(pad "2" smd rect
			(at 0 0.889 180)
			(size 0.508 0.508)
			(layers "F.Cu" "F.Mask" "F.Paste")
			(net "UART_MUX_IN_R")
		)
		(zone
			(layer "F.Cu")
			(hatch none 0.5)
			(connect_pads
				(clearance 0)
			)
			(min_thickness 0.25)
			(keepout
				(tracks not_allowed)
				(vias allowed)
				(pads allowed)
				(copperpour not_allowed)
				(footprints allowed)
			)
			(placement
				(enabled no)
				(sheetname "")
			)
			(fill
				(thermal_gap 0.5)
				(thermal_bridge_width 0.5)
				(island_removal_mode 0)
			)
			(polygon
				(pts
					(xy 489.228638 -29.06268) (xy 488.720638 -29.06268) (xy 488.720638 -28.68168) (xy 489.228638 -28.68168)
				)
			)
		)
		(zone
			(layer "F.Cu")
			(hatch none 0.5)
			(connect_pads
				(clearance 0)
			)
			(min_thickness 0.25)
			(keepout
				(tracks allowed)
				(vias not_allowed)
				(pads allowed)
				(copperpour not_allowed)
				(footprints allowed)
			)
			(placement
				(enabled no)
				(sheetname "")
			)
			(fill
				(thermal_gap 0.5)
				(thermal_bridge_width 0.5)
				(island_removal_mode 0)
			)
			(polygon
				(pts
					(xy 489.228638 -28.68168) (xy 488.720638 -28.68168) (xy 488.720638 -29.06268) (xy 489.228638 -29.06268)
				)
			)
		)
	)
	(footprint ""
		(layer "F.Cu")
		(at 188.22797 -60.461144 180)
		(property "Reference" "C4E9"
			(at 0 0 180)
			(layer "F.SilkS")
			(hide yes)
			(effects
				(font
					(size 1.27 1.27)
				)
			)
		)
		(property "Value" "*"
			(at -0.0762 -6.2357 180)
			(unlocked yes)
			(layer "F.Fab")
			(hide yes)
			(effects
				(font
					(size 1.27 1.016)
					(thickness 0.1524)
				)
			)
		)
		(property "Device Type" "SC22U16V5MX-4-GP_SMD-BCG5-SC22A"
			(at -0.0762 -8.2677 180)
			(unlocked yes)
			(layer "F.Fab")
			(hide yes)
			(effects
				(font
					(size 1.27 1.016)
					(thickness 0.1524)
				)
			)
		)
		(duplicate_pad_numbers_are_jumpers no)
		(fp_line
			(start 0.635 0)
			(end -0.635 0)
			(stroke
				(width 0.508)
				(type default)
			)
			(layer "F.SilkS")
		)
		(fp_rect
			(start -0.9652 1.778)
			(end 0.9652 -1.778)
			(stroke
				(width 0)
				(type default)
			)
			(fill no)
			(layer "F.CrtYd")
		)
		(fp_poly
			(pts
				(xy -0.9652 -1.778) (xy 0.9652 -1.778) (xy 0.9652 1.778) (xy -0.9652 1.778)
			)
			(stroke
				(width 0)
				(type default)
			)
			(fill no)
			(layer "F.Fab")
		)
		(pad "1" smd rect
			(at 0 -0.9652 180)
			(size 1.397 1.143)
			(layers "F.Cu" "F.Mask" "F.Paste")
			(net "VR_FET_SW_P12V_STBY_PVCCIN_CPU0")
		)
		(pad "2" smd rect
			(at 0 0.9652 180)
			(size 1.397 1.143)
			(layers "F.Cu" "F.Mask" "F.Paste")
			(net "GND")
		)
	)
	(footprint ""
		(layer "F.Cu")
		(at 193.653918 -80.363568 -90)
		(property "Reference" "R4D71"
			(at 0 0 270)
			(layer "F.SilkS")
			(hide yes)
			(effects
				(font
					(size 1.27 1.27)
				)
			)
		)
		(property "Value" ""
			(at 0 0 270)
			(layer "F.Fab")
			(effects
				(font
					(size 1.27 1.27)
				)
			)
		)
		(duplicate_pad_numbers_are_jumpers no)
		(fp_poly
			(pts
				(xy -0.2794 -0.1016) (xy 0.2794 -0.1016) (xy 0.2794 0.9906) (xy -0.2794 0.9906)
			)
			(stroke
				(width 0)
				(type default)
			)
			(fill no)
			(layer "F.CrtYd")
		)
		(fp_line
			(start -0.2794 0.9906)
			(end 0.2794 0.9906)
			(stroke
				(width 0.1)
				(type default)
			)
			(layer "F.Fab")
		)
		(fp_line
			(start 0.2794 0.9906)
			(end 0.2794 -0.1016)
			(stroke
				(width 0.1)
				(type default)
			)
			(layer "F.Fab")
		)
		(fp_line
			(start -0.2794 -0.1016)
			(end -0.2794 0.9906)
			(stroke
				(width 0.1)
				(type default)
			)
			(layer "F.Fab")
		)
		(fp_line
			(start 0.2794 -0.1016)
			(end -0.2794 -0.1016)
			(stroke
				(width 0.1)
				(type default)
			)
			(layer "F.Fab")
		)
		(pad "1" smd rect
			(at 0 0 270)
			(size 0.508 0.508)
			(layers "F.Cu" "F.Mask" "F.Paste")
			(net "VR_PVCCIN_CPU0_PH4_OCSET")
		)
		(pad "2" smd rect
			(at 0 0.889 270)
			(size 0.508 0.508)
			(layers "F.Cu" "F.Mask" "F.Paste")
			(net "GND")
		)
		(zone
			(layer "F.Cu")
			(hatch none 0.5)
			(connect_pads
				(clearance 0)
			)
			(min_thickness 0.25)
			(keepout
				(tracks not_allowed)
				(vias allowed)
				(pads allowed)
				(copperpour not_allowed)
				(footprints allowed)
			)
			(placement
				(enabled no)
				(sheetname "")
			)
			(fill
				(thermal_gap 0.5)
				(thermal_bridge_width 0.5)
				(island_removal_mode 0)
			)
			(polygon
				(pts
					(xy 193.018918 -80.617568) (xy 193.018918 -80.109568) (xy 193.399918 -80.109568) (xy 193.399918 -80.617568)
				)
			)
		)
		(zone
			(layer "F.Cu")
			(hatch none 0.5)
			(connect_pads
				(clearance 0)
			)
			(min_thickness 0.25)
			(keepout
				(tracks allowed)
				(vias not_allowed)
				(pads allowed)
				(copperpour not_allowed)
				(footprints allowed)
			)
			(placement
				(enabled no)
				(sheetname "")
			)
			(fill
				(thermal_gap 0.5)
				(thermal_bridge_width 0.5)
				(island_removal_mode 0)
			)
			(polygon
				(pts
					(xy 193.399918 -80.617568) (xy 193.399918 -80.109568) (xy 193.018918 -80.109568) (xy 193.018918 -80.617568)
				)
			)
		)
	)
)
